# S9S_MB_2U (Grand Teton) — schematic netlist excerpt (pin names and nets, part order shuffled) for the footprints in the layout excerpt that follows; sources: Cadence DE-HDL packaged netlist, KiCad conversion of 03242023_DA0F0TMBIJ0_F0T_Motherboard_J_brd_V01_OCP.brd

PC577_P1_2  Q_CAP  22UF 4V 20% X6S  pkg C0805  page 285 : A = PVCCIN_CPU1 ; B = GND
C452  Q_CAP  47UF 4V 20% X6S  pkg C0805  page 78 : A = PVCCFA_EHV_CPU1 ; B = GND
C120  Q_CAP  0.047UF 25V 10% X7R  pkg C0402  page 210 : A = P3V3_AUX_CLK_GEN_VDDPT_CK440 ; B = GND

(kicad_pcb
	(version 20260206)
	(generator "pcbnew")
	(generator_version "10.0")
	(general
		(thickness 1.6)
		(legacy_teardrops no)
	)
	(paper "A4")
	(title_block
		(title "03242023_DA0F0TMBIJ0_F0T_Motherboard_J_brd_V01_OCP.brd")
		(comment 1 "Grand Teton / footprints 4521-4523 of 6105")
	)
	(layers
		(0 "F.Cu" signal "TOP")
		(4 "In1.Cu" signal "GND")
		(6 "In2.Cu" signal "IN1")
		(8 "In3.Cu" signal "GND1")
		(10 "In4.Cu" signal "IN2")
		(12 "In5.Cu" signal "GND2")
		(14 "In6.Cu" signal "IN3")
		(16 "In7.Cu" signal "GND3")
		(18 "In8.Cu" signal "VCC")
		(20 "In9.Cu" signal "VCC1")
		(22 "In10.Cu" signal "GND4")
		(24 "In11.Cu" signal "IN4")
		(26 "In12.Cu" signal "GND5")
		(28 "In13.Cu" signal "IN5")
		(30 "In14.Cu" signal "GND6")
		(32 "In15.Cu" signal "IN6")
		(34 "In16.Cu" signal "GND7")
		(2 "B.Cu" signal "BOTTOM")
		(9 "F.Adhes" user "F.Adhesive")
		(11 "B.Adhes" user "B.Adhesive")
		(13 "F.Paste" user "Package Geometry/Pastemask Top")
		(15 "B.Paste" user "Package Geometry/Pastemask Bottom")
		(5 "F.SilkS" user "Ref Des/Silkscreen Top")
		(7 "B.SilkS" user "Ref Des/Silkscreen Bottom")
		(1 "F.Mask" user "Board Geometry/Soldermask Top")
		(3 "B.Mask" user "Board Geometry/Soldermask Bottom")
		(17 "Dwgs.User" user "User.Drawings")
		(19 "Cmts.User" user "User.Comments")
		(21 "Eco1.User" user "User.Eco1")
		(23 "Eco2.User" user "User.Eco2")
		(25 "Edge.Cuts" user "Board Geometry/Outline")
		(27 "Margin" user)
		(31 "F.CrtYd" user "Package Geometry/Place Bound Top")
		(29 "B.CrtYd" user "Package Geometry/Place Bound Bottom")
		(35 "F.Fab" user "Ref Des/Assembly Top")
		(33 "B.Fab" user "Ref Des/Assembly Bottom")
	)
	(footprint ""
		(layer "B.Cu")
		(at 252.222 -99.405948 180)
		(property "Reference" "C120"
			(at 0 0 0)
			(layer "B.SilkS")
			(hide yes)
			(effects
				(font
					(size 1.27 1.27)
				)
				(justify mirror)
			)
		)
		(property "Value" ""
			(at 0 0 0)
			(layer "B.Fab")
			(effects
				(font
					(size 1.27 1.27)
				)
				(justify mirror)
			)
		)
		(duplicate_pad_numbers_are_jumpers no)
		(fp_line
			(start 0.7874 0.4064)
			(end 0.7874 -0.4064)
			(stroke
				(width 0.1524)
				(type default)
			)
			(layer "B.SilkS")
		)
		(fp_line
			(start 0.7874 -0.4064)
			(end -0.7874 -0.4064)
			(stroke
				(width 0.1524)
				(type default)
			)
			(layer "B.SilkS")
		)
		(fp_line
			(start -0.7874 0.4064)
			(end 0.7874 0.4064)
			(stroke
				(width 0.1524)
				(type default)
			)
			(layer "B.SilkS")
		)
		(fp_line
			(start -0.7874 -0.4064)
			(end -0.7874 0.4064)
			(stroke
				(width 0.1524)
				(type default)
			)
			(layer "B.SilkS")
		)
		(fp_line
			(start 0.67945 0.3048)
			(end 0.67945 -0.305054)
			(stroke
				(width 0.1)
				(type default)
			)
			(layer "B.Fab")
		)
		(fp_line
			(start 0.67945 -0.305054)
			(end 0.12065 -0.305054)
			(stroke
				(width 0.1)
				(type default)
			)
			(layer "B.Fab")
		)
		(fp_line
			(start 0.12065 0.3048)
			(end 0.67945 0.3048)
			(stroke
				(width 0.1)
				(type default)
			)
			(layer "B.Fab")
		)
		(fp_line
			(start 0.12065 0.2794)
			(end 0.12065 0.3048)
			(stroke
				(width 0.1)
				(type default)
			)
			(layer "B.Fab")
		)
		(fp_line
			(start 0.12065 -0.2794)
			(end -0.12065 -0.2794)
			(stroke
				(width 0.1)
				(type default)
			)
			(layer "B.Fab")
		)
		(fp_line
			(start 0.12065 -0.305054)
			(end 0.12065 -0.2794)
			(stroke
				(width 0.1)
				(type default)
			)
			(layer "B.Fab")
		)
		(fp_line
			(start -0.120396 0.3048)
			(end -0.120396 0.2794)
			(stroke
				(width 0.1)
				(type default)
			)
			(layer "B.Fab")
		)
		(fp_line
			(start -0.120396 0.2794)
			(end 0.12065 0.2794)
			(stroke
				(width 0.1)
				(type default)
			)
			(layer "B.Fab")
		)
		(fp_line
			(start -0.12065 -0.2794)
			(end -0.12065 -0.3048)
			(stroke
				(width 0.1)
				(type default)
			)
			(layer "B.Fab")
		)
		(fp_line
			(start -0.12065 -0.3048)
			(end -0.67945 -0.3048)
			(stroke
				(width 0.1)
				(type default)
			)
			(layer "B.Fab")
		)
		(fp_line
			(start -0.67945 0.3048)
			(end -0.120396 0.3048)
			(stroke
				(width 0.1)
				(type default)
			)
			(layer "B.Fab")
		)
		(fp_line
			(start -0.67945 -0.3048)
			(end -0.67945 0.3048)
			(stroke
				(width 0.1)
				(type default)
			)
			(layer "B.Fab")
		)
		(pad "1" smd circle
			(at 0.40005 0)
			(size 0 0)
			(layers "B.Cu" "B.Mask" "B.Paste")
			(net "P3V3_AUX_CLK_GEN_VDDPT_CK440")
		)
		(pad "2" smd circle
			(at -0.40005 0)
			(size 0 0)
			(layers "B.Cu" "B.Mask" "B.Paste")
			(net "GND")
		)
	)
	(footprint ""
		(layer "B.Cu")
		(at 100.969572 -324.753986 -90)
		(property "Reference" "PC577_P1_2"
			(at 0 0 90)
			(layer "B.SilkS")
			(hide yes)
			(effects
				(font
					(size 1.27 1.27)
				)
				(justify mirror)
			)
		)
		(property "Value" ""
			(at 0 0 90)
			(layer "B.Fab")
			(effects
				(font
					(size 1.27 1.27)
				)
				(justify mirror)
			)
		)
		(duplicate_pad_numbers_are_jumpers no)
		(fp_line
			(start -1.524 0.762)
			(end 1.524 0.762)
			(stroke
				(width 0.1524)
				(type default)
			)
			(layer "B.SilkS")
		)
		(fp_line
			(start 1.524 0.762)
			(end 1.524 -0.762)
			(stroke
				(width 0.1524)
				(type default)
			)
			(layer "B.SilkS")
		)
		(fp_line
			(start -1.524 -0.762)
			(end -1.524 0.762)
			(stroke
				(width 0.1524)
				(type default)
			)
			(layer "B.SilkS")
		)
		(fp_line
			(start 1.524 -0.762)
			(end -1.524 -0.762)
			(stroke
				(width 0.1524)
				(type default)
			)
			(layer "B.SilkS")
		)
		(fp_line
			(start -1.1049 0.724916)
			(end -1.1049 -0.724916)
			(stroke
				(width 0.1)
				(type default)
			)
			(layer "B.Fab")
		)
		(fp_line
			(start 1.1049 0.724916)
			(end -1.1049 0.724916)
			(stroke
				(width 0.1)
				(type default)
			)
			(layer "B.Fab")
		)
		(fp_line
			(start -1.1049 -0.724916)
			(end 1.1049 -0.724916)
			(stroke
				(width 0.1)
				(type default)
			)
			(layer "B.Fab")
		)
		(fp_line
			(start 1.1049 -0.724916)
			(end 1.1049 0.724916)
			(stroke
				(width 0.1)
				(type default)
			)
			(layer "B.Fab")
		)
		(pad "1" smd rect
			(at 0.889 0 270)
			(size 1.016 1.27)
			(layers "B.Cu" "B.Mask" "B.Paste")
			(net "PVCCIN_CPU1")
		)
		(pad "2" smd rect
			(at -0.889 0 270)
			(size 1.016 1.27)
			(layers "B.Cu" "B.Mask" "B.Paste")
			(net "GND")
		)
	)
	(footprint ""
		(layer "B.Cu")
		(at 103.901494 -255.8542 90)
		(property "Reference" "C452"
			(at 0 0 90)
			(layer "B.SilkS")
			(hide yes)
			(effects
				(font
					(size 1.27 1.27)
				)
				(justify mirror)
			)
		)
		(property "Value" ""
			(at 0 0 90)
			(layer "B.Fab")
			(effects
				(font
					(size 1.27 1.27)
				)
				(justify mirror)
			)
		)
		(duplicate_pad_numbers_are_jumpers no)
		(fp_line
			(start 1.524 -0.762)
			(end -1.524 -0.762)
			(stroke
				(width 0.1524)
				(type default)
			)
			(layer "B.SilkS")
		)
		(fp_line
			(start -1.524 -0.762)
			(end -1.524 0.762)
			(stroke
				(width 0.1524)
				(type default)
			)
			(layer "B.SilkS")
		)
		(fp_line
			(start 1.524 0.762)
			(end 1.524 -0.762)
			(stroke
				(width 0.1524)
				(type default)
			)
			(layer "B.SilkS")
		)
		(fp_line
			(start -1.524 0.762)
			(end 1.524 0.762)
			(stroke
				(width 0.1524)
				(type default)
			)
			(layer "B.SilkS")
		)
		(fp_line
			(start 1.1049 -0.724916)
			(end 1.1049 0.724916)
			(stroke
				(width 0.1)
				(type default)
			)
			(layer "B.Fab")
		)
		(fp_line
			(start -1.1049 -0.724916)
			(end 1.1049 -0.724916)
			(stroke
				(width 0.1)
				(type default)
			)
			(layer "B.Fab")
		)
		(fp_line
			(start 1.1049 0.724916)
			(end -1.1049 0.724916)
			(stroke
				(width 0.1)
				(type default)
			)
			(layer "B.Fab")
		)
		(fp_line
			(start -1.1049 0.724916)
			(end -1.1049 -0.724916)
			(stroke
				(width 0.1)
				(type default)
			)
			(layer "B.Fab")
		)
		(pad "1" smd rect
			(at 0.889 0 90)
			(size 1.016 1.27)
			(layers "B.Cu" "B.Mask" "B.Paste")
			(net "PVCCFA_EHV_CPU1")
		)
		(pad "2" smd rect
			(at -0.889 0 90)
			(size 1.016 1.27)
			(layers "B.Cu" "B.Mask" "B.Paste")
			(net "GND")
		)
	)
)
